# S9S_MB_2U (Grand Teton) — schematic netlist excerpt (pin names and nets, part order shuffled) for the footprints in the layout excerpt that follows; sources: Cadence DE-HDL packaged netlist, KiCad conversion of 03242023_DA0F0TMBIJ0_F0T_Motherboard_J_brd_V01_OCP.brd

R2674  Q_RES  27.4 1% CHIP  pkg 0402LF  page 234 : A = I3C_BMC_SWB_BUF_R_SDA ; B = I3C_BMC_SWB_BUF_SDA
R1906  Q_RES  1K 1% CHIP  pkg 0402LF  page 156 : A = P3V3_AUX ; B = OCP_SFF_PRSNT2_R_N

(kicad_pcb
	(version 20260206)
	(generator "pcbnew")
	(generator_version "10.0")
	(general
		(thickness 1.6)
		(legacy_teardrops no)
	)
	(paper "A4")
	(title_block
		(title "03242023_DA0F0TMBIJ0_F0T_Motherboard_J_brd_V01_OCP.brd")
		(comment 1 "Grand Teton / footprints 1579-1580 of 6105")
	)
	(layers
		(0 "F.Cu" signal "TOP")
		(4 "In1.Cu" signal "GND")
		(6 "In2.Cu" signal "IN1")
		(8 "In3.Cu" signal "GND1")
		(10 "In4.Cu" signal "IN2")
		(12 "In5.Cu" signal "GND2")
		(14 "In6.Cu" signal "IN3")
		(16 "In7.Cu" signal "GND3")
		(18 "In8.Cu" signal "VCC")
		(20 "In9.Cu" signal "VCC1")
		(22 "In10.Cu" signal "GND4")
		(24 "In11.Cu" signal "IN4")
		(26 "In12.Cu" signal "GND5")
		(28 "In13.Cu" signal "IN5")
		(30 "In14.Cu" signal "GND6")
		(32 "In15.Cu" signal "IN6")
		(34 "In16.Cu" signal "GND7")
		(2 "B.Cu" signal "BOTTOM")
		(9 "F.Adhes" user "F.Adhesive")
		(11 "B.Adhes" user "B.Adhesive")
		(13 "F.Paste" user "Package Geometry/Pastemask Top")
		(15 "B.Paste" user "Package Geometry/Pastemask Bottom")
		(5 "F.SilkS" user "Ref Des/Silkscreen Top")
		(7 "B.SilkS" user "Ref Des/Silkscreen Bottom")
		(1 "F.Mask" user "Board Geometry/Soldermask Top")
		(3 "B.Mask" user "Board Geometry/Soldermask Bottom")
		(17 "Dwgs.User" user "User.Drawings")
		(19 "Cmts.User" user "User.Comments")
		(21 "Eco1.User" user "User.Eco1")
		(23 "Eco2.User" user "User.Eco2")
		(25 "Edge.Cuts" user "Board Geometry/Outline")
		(27 "Margin" user)
		(31 "F.CrtYd" user "Package Geometry/Place Bound Top")
		(29 "B.CrtYd" user "Package Geometry/Place Bound Bottom")
		(35 "F.Fab" user "Ref Des/Assembly Top")
		(33 "B.Fab" user "Ref Des/Assembly Bottom")
	)
	(footprint ""
		(layer "F.Cu")
		(at 453.719946 -104.249728)
		(property "Reference" "R1906"
			(at 0 0 0)
			(layer "F.SilkS")
			(hide yes)
			(effects
				(font
					(size 1.27 1.27)
				)
			)
		)
		(property "Value" ""
			(at 0 0 0)
			(layer "F.Fab")
			(effects
				(font
					(size 1.27 1.27)
				)
			)
		)
		(duplicate_pad_numbers_are_jumpers no)
		(fp_line
			(start -0.7874 -0.4064)
			(end 0.7874 -0.4064)
			(stroke
				(width 0.1524)
				(type default)
			)
			(layer "F.SilkS")
		)
		(fp_line
			(start -0.7874 0.4064)
			(end -0.7874 -0.4064)
			(stroke
				(width 0.1524)
				(type default)
			)
			(layer "F.SilkS")
		)
		(fp_line
			(start 0.7874 -0.4064)
			(end 0.7874 0.4064)
			(stroke
				(width 0.1524)
				(type default)
			)
			(layer "F.SilkS")
		)
		(fp_line
			(start 0.7874 0.4064)
			(end -0.7874 0.4064)
			(stroke
				(width 0.1524)
				(type default)
			)
			(layer "F.SilkS")
		)
		(fp_line
			(start -0.67945 -0.305054)
			(end -0.12065 -0.305054)
			(stroke
				(width 0.1)
				(type default)
			)
			(layer "F.Fab")
		)
		(fp_line
			(start -0.67945 0.3048)
			(end -0.67945 -0.305054)
			(stroke
				(width 0.1)
				(type default)
			)
			(layer "F.Fab")
		)
		(fp_line
			(start -0.12065 -0.305054)
			(end -0.12065 -0.2794)
			(stroke
				(width 0.1)
				(type default)
			)
			(layer "F.Fab")
		)
		(fp_line
			(start -0.12065 -0.2794)
			(end 0.12065 -0.2794)
			(stroke
				(width 0.1)
				(type default)
			)
			(layer "F.Fab")
		)
		(fp_line
			(start -0.12065 0.2794)
			(end -0.12065 0.3048)
			(stroke
				(width 0.1)
				(type default)
			)
			(layer "F.Fab")
		)
		(fp_line
			(start -0.12065 0.3048)
			(end -0.67945 0.3048)
			(stroke
				(width 0.1)
				(type default)
			)
			(layer "F.Fab")
		)
		(fp_line
			(start 0.120396 0.2794)
			(end -0.12065 0.2794)
			(stroke
				(width 0.1)
				(type default)
			)
			(layer "F.Fab")
		)
		(fp_line
			(start 0.120396 0.3048)
			(end 0.120396 0.2794)
			(stroke
				(width 0.1)
				(type default)
			)
			(layer "F.Fab")
		)
		(fp_line
			(start 0.12065 -0.3048)
			(end 0.67945 -0.3048)
			(stroke
				(width 0.1)
				(type default)
			)
			(layer "F.Fab")
		)
		(fp_line
			(start 0.12065 -0.2794)
			(end 0.12065 -0.3048)
			(stroke
				(width 0.1)
				(type default)
			)
			(layer "F.Fab")
		)
		(fp_line
			(start 0.67945 -0.3048)
			(end 0.67945 0.3048)
			(stroke
				(width 0.1)
				(type default)
			)
			(layer "F.Fab")
		)
		(fp_line
			(start 0.67945 0.3048)
			(end 0.120396 0.3048)
			(stroke
				(width 0.1)
				(type default)
			)
			(layer "F.Fab")
		)
		(pad "1" smd circle
			(at -0.40005 0)
			(size 0 0)
			(layers "F.Cu" "F.Mask" "F.Paste")
			(net "P3V3_AUX")
		)
		(pad "2" smd circle
			(at 0.40005 0)
			(size 0 0)
			(layers "F.Cu" "F.Mask" "F.Paste")
			(net "OCP_SFF_PRSNT2_R_N")
		)
	)
	(footprint ""
		(layer "F.Cu")
		(at 354.687632 -397.519398 180)
		(property "Reference" "R2674"
			(at 0 0 180)
			(layer "F.SilkS")
			(hide yes)
			(effects
				(font
					(size 1.27 1.27)
				)
			)
		)
		(property "Value" ""
			(at 0 0 180)
			(layer "F.Fab")
			(effects
				(font
					(size 1.27 1.27)
				)
			)
		)
		(duplicate_pad_numbers_are_jumpers no)
		(fp_line
			(start 0.7874 0.4064)
			(end -0.7874 0.4064)
			(stroke
				(width 0.1524)
				(type default)
			)
			(layer "F.SilkS")
		)
		(fp_line
			(start 0.7874 -0.4064)
			(end 0.7874 0.4064)
			(stroke
				(width 0.1524)
				(type default)
			)
			(layer "F.SilkS")
		)
		(fp_line
			(start -0.7874 0.4064)
			(end -0.7874 -0.4064)
			(stroke
				(width 0.1524)
				(type default)
			)
			(layer "F.SilkS")
		)
		(fp_line
			(start -0.7874 -0.4064)
			(end 0.7874 -0.4064)
			(stroke
				(width 0.1524)
				(type default)
			)
			(layer "F.SilkS")
		)
		(fp_line
			(start 0.67945 0.3048)
			(end 0.120396 0.3048)
			(stroke
				(width 0.1)
				(type default)
			)
			(layer "F.Fab")
		)
		(fp_line
			(start 0.67945 -0.3048)
			(end 0.67945 0.3048)
			(stroke
				(width 0.1)
				(type default)
			)
			(layer "F.Fab")
		)
		(fp_line
			(start 0.12065 -0.2794)
			(end 0.12065 -0.3048)
			(stroke
				(width 0.1)
				(type default)
			)
			(layer "F.Fab")
		)
		(fp_line
			(start 0.12065 -0.3048)
			(end 0.67945 -0.3048)
			(stroke
				(width 0.1)
				(type default)
			)
			(layer "F.Fab")
		)
		(fp_line
			(start 0.120396 0.3048)
			(end 0.120396 0.2794)
			(stroke
				(width 0.1)
				(type default)
			)
			(layer "F.Fab")
		)
		(fp_line
			(start 0.120396 0.2794)
			(end -0.12065 0.2794)
			(stroke
				(width 0.1)
				(type default)
			)
			(layer "F.Fab")
		)
		(fp_line
			(start -0.12065 0.3048)
			(end -0.67945 0.3048)
			(stroke
				(width 0.1)
				(type default)
			)
			(layer "F.Fab")
		)
		(fp_line
			(start -0.12065 0.2794)
			(end -0.12065 0.3048)
			(stroke
				(width 0.1)
				(type default)
			)
			(layer "F.Fab")
		)
		(fp_line
			(start -0.12065 -0.2794)
			(end 0.12065 -0.2794)
			(stroke
				(width 0.1)
				(type default)
			)
			(layer "F.Fab")
		)
		(fp_line
			(start -0.12065 -0.305054)
			(end -0.12065 -0.2794)
			(stroke
				(width 0.1)
				(type default)
			)
			(layer "F.Fab")
		)
		(fp_line
			(start -0.67945 0.3048)
			(end -0.67945 -0.305054)
			(stroke
				(width 0.1)
				(type default)
			)
			(layer "F.Fab")
		)
		(fp_line
			(start -0.67945 -0.305054)
			(end -0.12065 -0.305054)
			(stroke
				(width 0.1)
				(type default)
			)
			(layer "F.Fab")
		)
		(pad "1" smd circle
			(at -0.40005 0 180)
			(size 0 0)
			(layers "F.Cu" "F.Mask" "F.Paste")
			(net "I3C_BMC_SWB_BUF_R_SDA")
		)
		(pad "2" smd circle
			(at 0.40005 0 180)
			(size 0 0)
			(layers "F.Cu" "F.Mask" "F.Paste")
			(net "I3C_BMC_SWB_BUF_SDA")
		)
	)
)
